# BASEBOARD_FAB2 (Tioga Pass) — schematic netlist excerpt (pin names and nets, part order shuffled) for the footprints in the layout excerpt that follows; sources: Cadence DE-HDL packaged netlist, KiCad conversion of Wiwynn_Tioga_Pass_MB.brd

R25W48  120R2F-GP  1%  pkg RCL_GP  page 151 : \1\ = BMC_M_A10 ; \2\ = P1V2_AUX_BMC
C2R17  CAP_A  0.1UF 16V 10% X7R  pkg 0402V  page 188 : A = P12V_STBY ; B = GND
C6P5  CAP_A  0.1UF 16V 10% X7R  pkg 0402V  page 102 : A = P3V3_DB1200 ; B = GND

(kicad_pcb
	(version 20260206)
	(generator "pcbnew")
	(generator_version "10.0")
	(general
		(thickness 1.6)
		(legacy_teardrops no)
	)
	(paper "A4")
	(title_block
		(title "Wiwynn_Tioga_Pass_MB.brd")
		(comment 1 "Tioga Pass / footprints 4276-4278 of 4770")
	)
	(layers
		(0 "F.Cu" signal "TOP")
		(4 "In1.Cu" signal "L2GND")
		(6 "In2.Cu" signal "L3")
		(8 "In3.Cu" signal "L4GND")
		(10 "In4.Cu" signal "L5")
		(12 "In5.Cu" signal "L6GND")
		(14 "In6.Cu" signal "L7VCC")
		(16 "In7.Cu" signal "L8VCC")
		(18 "In8.Cu" signal "L9GND")
		(20 "In9.Cu" signal "L10")
		(22 "In10.Cu" signal "L11GND")
		(24 "In11.Cu" signal "L12")
		(26 "In12.Cu" signal "L13GND")
		(2 "B.Cu" signal "BOTTOM")
		(9 "F.Adhes" user "F.Adhesive")
		(11 "B.Adhes" user "B.Adhesive")
		(13 "F.Paste" user "Package Geometry/Pastemask Top")
		(15 "B.Paste" user "Package Geometry/Pastemask Bottom")
		(5 "F.SilkS" user "Ref Des/Silkscreen Top")
		(7 "B.SilkS" user "Ref Des/Silkscreen Bottom")
		(1 "F.Mask" user "Board Geometry/Soldermask Top")
		(3 "B.Mask" user "Board Geometry/Soldermask Bottom")
		(17 "Dwgs.User" user "User.Drawings")
		(19 "Cmts.User" user "User.Comments")
		(21 "Eco1.User" user "User.Eco1")
		(23 "Eco2.User" user "User.Eco2")
		(25 "Edge.Cuts" user "Board Geometry/Outline")
		(27 "Margin" user)
		(31 "F.CrtYd" user "Package Geometry/Place Bound Top")
		(29 "B.CrtYd" user "Package Geometry/Place Bound Bottom")
		(35 "F.Fab" user "Ref Des/Assembly Top")
		(33 "B.Fab" user "Ref Des/Assembly Bottom")
	)
	(footprint ""
		(layer "B.Cu")
		(at 437.515 -52.3875)
		(property "Reference" "C2R17"
			(at 0 0 0)
			(layer "B.SilkS")
			(hide yes)
			(effects
				(font
					(size 1.27 1.27)
				)
				(justify mirror)
			)
		)
		(property "Value" ""
			(at 0 0 0)
			(layer "B.Fab")
			(effects
				(font
					(size 1.27 1.27)
				)
				(justify mirror)
			)
		)
		(duplicate_pad_numbers_are_jumpers no)
		(fp_poly
			(pts
				(xy -0.3048 -0.1016) (xy -0.3048 0.9906) (xy 0.3048 0.9906) (xy 0.3048 -0.1016)
			)
			(stroke
				(width 0)
				(type default)
			)
			(fill no)
			(layer "B.CrtYd")
		)
		(fp_line
			(start -0.3048 -0.1016)
			(end 0.3048 -0.1016)
			(stroke
				(width 0.1)
				(type default)
			)
			(layer "B.Fab")
		)
		(fp_line
			(start -0.3048 0.9906)
			(end -0.3048 -0.1016)
			(stroke
				(width 0.1)
				(type default)
			)
			(layer "B.Fab")
		)
		(fp_line
			(start 0.3048 -0.1016)
			(end 0.3048 0.9906)
			(stroke
				(width 0.1)
				(type default)
			)
			(layer "B.Fab")
		)
		(fp_line
			(start 0.3048 0.9906)
			(end -0.3048 0.9906)
			(stroke
				(width 0.1)
				(type default)
			)
			(layer "B.Fab")
		)
		(pad "1" smd rect
			(at 0 0 180)
			(size 0.508 0.508)
			(layers "B.Cu" "B.Mask" "B.Paste")
			(net "P12V_STBY")
		)
		(pad "2" smd rect
			(at 0 0.889 180)
			(size 0.508 0.508)
			(layers "B.Cu" "B.Mask" "B.Paste")
			(net "GND")
		)
		(zone
			(layer "B.Cu")
			(hatch none 0.5)
			(connect_pads
				(clearance 0)
			)
			(min_thickness 0.25)
			(keepout
				(tracks allowed)
				(vias not_allowed)
				(pads allowed)
				(copperpour not_allowed)
				(footprints allowed)
			)
			(placement
				(enabled no)
				(sheetname "")
			)
			(fill
				(thermal_gap 0.5)
				(thermal_bridge_width 0.5)
				(island_removal_mode 0)
			)
			(polygon
				(pts
					(xy 437.769 -52.1335) (xy 437.261 -52.1335) (xy 437.261 -51.7525) (xy 437.769 -51.7525)
				)
			)
		)
		(zone
			(layer "B.Cu")
			(hatch none 0.5)
			(connect_pads
				(clearance 0)
			)
			(min_thickness 0.25)
			(keepout
				(tracks not_allowed)
				(vias allowed)
				(pads allowed)
				(copperpour not_allowed)
				(footprints allowed)
			)
			(placement
				(enabled no)
				(sheetname "")
			)
			(fill
				(thermal_gap 0.5)
				(thermal_bridge_width 0.5)
				(island_removal_mode 0)
			)
			(polygon
				(pts
					(xy 437.769 -51.7525) (xy 437.261 -51.7525) (xy 437.261 -52.1335) (xy 437.769 -52.1335)
				)
			)
		)
	)
	(footprint ""
		(layer "B.Cu")
		(at 164.973 -84.709 90)
		(property "Reference" "C6P5"
			(at 0 0 90)
			(layer "B.SilkS")
			(hide yes)
			(effects
				(font
					(size 1.27 1.27)
				)
				(justify mirror)
			)
		)
		(property "Value" ""
			(at 0 0 90)
			(layer "B.Fab")
			(effects
				(font
					(size 1.27 1.27)
				)
				(justify mirror)
			)
		)
		(duplicate_pad_numbers_are_jumpers no)
		(fp_poly
			(pts
				(xy -0.3048 -0.1016) (xy -0.3048 0.9906) (xy 0.3048 0.9906) (xy 0.3048 -0.1016)
			)
			(stroke
				(width 0)
				(type default)
			)
			(fill no)
			(layer "B.CrtYd")
		)
		(fp_line
			(start 0.3048 -0.1016)
			(end 0.3048 0.9906)
			(stroke
				(width 0.1)
				(type default)
			)
			(layer "B.Fab")
		)
		(fp_line
			(start -0.3048 -0.1016)
			(end 0.3048 -0.1016)
			(stroke
				(width 0.1)
				(type default)
			)
			(layer "B.Fab")
		)
		(fp_line
			(start 0.3048 0.9906)
			(end -0.3048 0.9906)
			(stroke
				(width 0.1)
				(type default)
			)
			(layer "B.Fab")
		)
		(fp_line
			(start -0.3048 0.9906)
			(end -0.3048 -0.1016)
			(stroke
				(width 0.1)
				(type default)
			)
			(layer "B.Fab")
		)
		(pad "1" smd rect
			(at 0 0 270)
			(size 0.508 0.508)
			(layers "B.Cu" "B.Mask" "B.Paste")
			(net "P3V3_DB1200")
		)
		(pad "2" smd rect
			(at 0 0.889 270)
			(size 0.508 0.508)
			(layers "B.Cu" "B.Mask" "B.Paste")
			(net "GND")
		)
		(zone
			(layer "B.Cu")
			(hatch none 0.5)
			(connect_pads
				(clearance 0)
			)
			(min_thickness 0.25)
			(keepout
				(tracks allowed)
				(vias not_allowed)
				(pads allowed)
				(copperpour not_allowed)
				(footprints allowed)
			)
			(placement
				(enabled no)
				(sheetname "")
			)
			(fill
				(thermal_gap 0.5)
				(thermal_bridge_width 0.5)
				(island_removal_mode 0)
			)
			(polygon
				(pts
					(xy 165.227 -84.963) (xy 165.227 -84.455) (xy 165.608 -84.455) (xy 165.608 -84.963)
				)
			)
		)
		(zone
			(layer "B.Cu")
			(hatch none 0.5)
			(connect_pads
				(clearance 0)
			)
			(min_thickness 0.25)
			(keepout
				(tracks not_allowed)
				(vias allowed)
				(pads allowed)
				(copperpour not_allowed)
				(footprints allowed)
			)
			(placement
				(enabled no)
				(sheetname "")
			)
			(fill
				(thermal_gap 0.5)
				(thermal_bridge_width 0.5)
				(island_removal_mode 0)
			)
			(polygon
				(pts
					(xy 165.608 -84.963) (xy 165.608 -84.455) (xy 165.227 -84.455) (xy 165.227 -84.963)
				)
			)
		)
	)
	(footprint ""
		(layer "B.Cu")
		(at 448.55638 -34.7345 90)
		(property "Reference" "R25W48"
			(at 0 0 90)
			(layer "B.SilkS")
			(hide yes)
			(effects
				(font
					(size 1.27 1.27)
				)
				(justify mirror)
			)
		)
		(property "Value" "*"
			(at -0.064008 -4.108196 90)
			(unlocked yes)
			(layer "B.Fab")
			(hide yes)
			(effects
				(font
					(size 1.27 1.016)
					(thickness 0.1524)
				)
				(justify mirror)
			)
		)
		(property "Device Type" "120R2F-GP_RCL_GP-120R2F-GP,64.A"
			(at -0.064008 -5.632196 90)
			(unlocked yes)
			(layer "B.Fab")
			(hide yes)
			(effects
				(font
					(size 1.27 1.016)
					(thickness 0.1524)
				)
				(justify mirror)
			)
		)
		(duplicate_pad_numbers_are_jumpers no)
		(fp_line
			(start 0.508 -0.9398)
			(end 0.508 0.9398)
			(stroke
				(width 0.1524)
				(type default)
			)
			(layer "B.SilkS")
		)
		(fp_line
			(start -0.508 -0.9398)
			(end 0.508 -0.9398)
			(stroke
				(width 0.1524)
				(type default)
			)
			(layer "B.SilkS")
		)
		(fp_rect
			(start 0.508 0.9398)
			(end -0.508 -0.9398)
			(stroke
				(width 0)
				(type default)
			)
			(fill no)
			(layer "B.CrtYd")
		)
		(fp_rect
			(start 0.508 0.9398)
			(end -0.508 -0.9398)
			(stroke
				(width 0)
				(type default)
			)
			(fill no)
			(layer "B.Fab")
		)
		(pad "1" smd custom
			(at 0 -0.4445 270)
			(size 0.1397 0.1397)
			(layers "B.Cu" "B.Mask" "B.Paste")
			(net "BMC_M_A10")
			(options
				(clearance outline)
				(anchor circle)
			)
			(primitives
				(gr_poly
					(pts
						(arc
							(start -0.1778 0.2794)
							(mid -0.249642 0.249642)
							(end -0.2794 0.1778)
						)
						(arc
							(start -0.2794 -0.1778)
							(mid -0.249642 -0.249642)
							(end -0.1778 -0.2794)
						)
						(arc
							(start 0.1778 -0.2794)
							(mid 0.249642 -0.249642)
							(end 0.2794 -0.1778)
						)
						(arc
							(start 0.2794 0.1778)
							(mid 0.249642 0.249642)
							(end 0.1778 0.2794)
						)
					)
					(width 0)
					(fill yes)
				)
			)
		)
		(pad "2" smd custom
			(at 0 0.4445 270)
			(size 0.1397 0.1397)
			(layers "B.Cu" "B.Mask" "B.Paste")
			(net "P1V2_AUX_BMC")
			(options
				(clearance outline)
				(anchor circle)
			)
			(primitives
				(gr_poly
					(pts
						(arc
							(start -0.1778 0.2794)
							(mid -0.249642 0.249642)
							(end -0.2794 0.1778)
						)
						(arc
							(start -0.2794 -0.1778)
							(mid -0.249642 -0.249642)
							(end -0.1778 -0.2794)
						)
						(arc
							(start 0.1778 -0.2794)
							(mid 0.249642 -0.249642)
							(end 0.2794 -0.1778)
						)
						(arc
							(start 0.2794 0.1778)
							(mid 0.249642 0.249642)
							(end 0.1778 0.2794)
						)
					)
					(width 0)
					(fill yes)
				)
			)
		)
	)
)
